(kicad_pcb
	(version 20241229)
	(generator "pcbnew")
	(generator_version "9.0")
	(general
		(thickness 1.62)
		(legacy_teardrops no)
	)
	(paper "A3")
	(title_block
		(title "COM Express 7 Baseboard")
		(date "2025-02-04")
		(rev "1.1.2")
		(company "Antmicro Ltd")
		(comment 1 "www.antmicro.com")
		(comment 9 "footprints 269-273 of 802")
	)
	(layers
		(0 "F.Cu" signal)
		(4 "In1.Cu" signal)
		(6 "In2.Cu" signal)
		(8 "In3.Cu" signal)
		(10 "In4.Cu" signal)
		(12 "In5.Cu" signal)
		(14 "In6.Cu" signal)
		(2 "B.Cu" signal)
		(9 "F.Adhes" user "F.Adhesive")
		(11 "B.Adhes" user "B.Adhesive")
		(13 "F.Paste" user)
		(15 "B.Paste" user)
		(5 "F.SilkS" user "F.Silkscreen")
		(7 "B.SilkS" user "B.Silkscreen")
		(1 "F.Mask" user)
		(3 "B.Mask" user)
		(17 "Dwgs.User" user "User.Drawings")
		(19 "Cmts.User" user "User.Comments")
		(21 "Eco1.User" user "User.Eco1")
		(23 "Eco2.User" user "User.Eco2")
		(25 "Edge.Cuts" user)
		(27 "Margin" user)
		(31 "F.CrtYd" user "F.Courtyard")
		(29 "B.CrtYd" user "B.Courtyard")
		(35 "F.Fab" user)
		(33 "B.Fab" user)
	)
	(footprint "antmicro-footprints:C_0402_1005Metric"
		(layer "F.Cu")
		(at 143 141.86)
		(descr "Capacitor SMD 0402")
		(tags "capacitor SMD 0402")
		(property "Reference" "C152"
			(at -3.55 0.4 0)
			(layer "F.SilkS")
			(effects
				(font
					(size 0.7 0.7)
					(thickness 0.15)
				)
				(justify left bottom)
			)
		)
		(property "Value" "C_100n_0402"
			(at -1.022927 2.155213 0)
			(layer "F.Fab")
			(effects
				(font
					(size 0.7 0.7)
					(thickness 0.15)
				)
				(justify left bottom)
			)
		)
		(property "Datasheet" "https://www.murata.com/products/productdetail?partno=GRM155R61H104KE14%23"
			(at 0 0 0)
			(layer "F.Fab")
			(hide yes)
			(effects
				(font
					(size 1.27 1.27)
					(thickness 0.15)
				)
			)
		)
		(property "Author" "Antmicro"
			(at 0 0 0)
			(layer "F.Fab")
			(hide yes)
			(effects
				(font
					(size 1 1)
					(thickness 0.15)
				)
			)
		)
		(property "Dielectric" "X5R"
			(at 0 0 0)
			(layer "F.Fab")
			(hide yes)
			(effects
				(font
					(size 1 1)
					(thickness 0.15)
				)
			)
		)
		(property "License" "Apache-2.0"
			(at 0 0 0)
			(layer "F.Fab")
			(hide yes)
			(effects
				(font
					(size 1 1)
					(thickness 0.15)
				)
			)
		)
		(property "MPN" "GRM155R61H104KE14D"
			(at 0 0 0)
			(layer "F.Fab")
			(hide yes)
			(effects
				(font
					(size 1 1)
					(thickness 0.15)
				)
			)
		)
		(property "Manufacturer" "Murata"
			(at 0 0 0)
			(layer "F.Fab")
			(hide yes)
			(effects
				(font
					(size 1 1)
					(thickness 0.15)
				)
			)
		)
		(property "Public" "False"
			(at 0 0 0)
			(layer "F.Fab")
			(hide yes)
			(effects
				(font
					(size 1 1)
					(thickness 0.15)
				)
			)
		)
		(property "Val" "100n"
			(at 0 0 0)
			(layer "F.Fab")
			(hide yes)
			(effects
				(font
					(size 1 1)
					(thickness 0.15)
				)
			)
		)
		(property "Voltage" "50V"
			(at 0 0 0)
			(layer "F.Fab")
			(hide yes)
			(effects
				(font
					(size 1 1)
					(thickness 0.15)
				)
			)
		)
		(sheetname "KR to SFI #1")
		(sheetfile "kr_sfi.kicad_sch")
		(attr smd)
		(fp_rect
			(start -0.925 -0.47)
			(end 0.925 0.47)
			(stroke
				(width 0.05)
				(type default)
			)
			(fill no)
			(layer "F.CrtYd")
		)
		(fp_line
			(start -0.494 -0.25)
			(end 0.504 -0.25)
			(stroke
				(width 0.15)
				(type solid)
			)
			(layer "F.Fab")
		)
		(fp_line
			(start -0.494 0.248)
			(end -0.494 -0.25)
			(stroke
				(width 0.15)
				(type solid)
			)
			(layer "F.Fab")
		)
		(fp_line
			(start 0.504 -0.25)
			(end 0.504 0.248)
			(stroke
				(width 0.15)
				(type solid)
			)
			(layer "F.Fab")
		)
		(fp_line
			(start 0.504 0.248)
			(end -0.494 0.248)
			(stroke
				(width 0.15)
				(type solid)
			)
			(layer "F.Fab")
		)
		(pad "1" smd roundrect
			(at -0.48 0)
			(size 0.59 0.64)
			(layers "F.Cu" "F.Mask" "F.Paste")
			(roundrect_rratio 0.25)
			(net 107 "/2xSFP+/KR to SFI #1/CLK+")
			(pintype "passive")
			(teardrops
				(best_length_ratio 0.2)
				(max_length 1)
				(best_width_ratio 0.9)
				(max_width 2)
				(curved_edges yes)
				(filter_ratio 0.9)
				(enabled yes)
				(allow_two_segments yes)
				(prefer_zone_connections yes)
			)
		)
		(pad "2" smd roundrect
			(at 0.48 0)
			(size 0.59 0.64)
			(layers "F.Cu" "F.Mask" "F.Paste")
			(roundrect_rratio 0.25)
			(net 110 "/2xSFP+/KR to SFI #1/REFCLK-")
			(pintype "passive")
			(teardrops
				(best_length_ratio 0.2)
				(max_length 1)
				(best_width_ratio 0.9)
				(max_width 2)
				(curved_edges yes)
				(filter_ratio 0.9)
				(enabled yes)
				(allow_two_segments yes)
				(prefer_zone_connections yes)
			)
		)
	)
	(footprint "antmicro-footprints:F_1206_3216Metric"
		(layer "F.Cu")
		(at 298.9 142.21 180)
		(property "Reference" "F3"
			(at -0.7 1.2 0)
			(layer "F.SilkS")
			(effects
				(font
					(size 0.7 0.7)
					(thickness 0.15)
				)
				(justify right bottom)
			)
		)
		(property "Value" "PTC_4.5A_1206"
			(at 0 2 0)
			(layer "F.Fab")
			(effects
				(font
					(size 0.7 0.7)
					(thickness 0.15)
				)
				(justify right bottom)
			)
		)
		(property "Datasheet" "http://www.farnell.com/datasheets/2282556.pdf"
			(at 0 0 180)
			(layer "F.Fab")
			(hide yes)
			(effects
				(font
					(size 1.27 1.27)
					(thickness 0.15)
				)
			)
		)
		(property "Author" "Antmicro"
			(at 597.8 284.42 0)
			(layer "F.Fab")
			(hide yes)
			(effects
				(font
					(size 1 1)
					(thickness 0.15)
				)
			)
		)
		(property "License" "Apache-2.0"
			(at 597.8 284.42 0)
			(layer "F.Fab")
			(hide yes)
			(effects
				(font
					(size 1 1)
					(thickness 0.15)
				)
			)
		)
		(property "MPN" "1206L450SLWR"
			(at 597.8 284.42 0)
			(layer "F.Fab")
			(hide yes)
			(effects
				(font
					(size 1 1)
					(thickness 0.15)
				)
			)
		)
		(property "Manufacturer" "Littelfuse"
			(at 597.8 284.42 0)
			(layer "F.Fab")
			(hide yes)
			(effects
				(font
					(size 1 1)
					(thickness 0.15)
				)
			)
		)
		(sheetname "Misc")
		(sheetfile "misc.kicad_sch")
		(attr smd)
		(fp_line
			(start 0.8 0.901)
			(end -0.8 0.901)
			(stroke
				(width 0.15)
				(type solid)
			)
			(layer "F.SilkS")
		)
		(fp_line
			(start 0.8 -0.899)
			(end -0.8 -0.899)
			(stroke
				(width 0.15)
				(type solid)
			)
			(layer "F.SilkS")
		)
		(fp_rect
			(start -2.325 -1.15)
			(end 2.325 1.15)
			(stroke
				(width 0.05)
				(type default)
			)
			(fill no)
			(layer "F.CrtYd")
		)
		(fp_line
			(start 1.624 0.792)
			(end -1.677 0.792)
			(stroke
				(width 0.15)
				(type solid)
			)
			(layer "F.Fab")
		)
		(fp_line
			(start 1.624 -0.861)
			(end 1.624 0.792)
			(stroke
				(width 0.15)
				(type solid)
			)
			(layer "F.Fab")
		)
		(fp_line
			(start -1.677 0.792)
			(end -1.677 -0.861)
			(stroke
				(width 0.15)
				(type solid)
			)
			(layer "F.Fab")
		)
		(fp_line
			(start -1.677 -0.861)
			(end 1.624 -0.861)
			(stroke
				(width 0.15)
				(type solid)
			)
			(layer "F.Fab")
		)
		(pad "1" smd roundrect
			(at -1.5 0.001 180)
			(size 1.15 1.8)
			(layers "F.Cu" "F.Mask" "F.Paste")
			(roundrect_rratio 0.25)
			(net 65 "+12V")
			(pintype "passive")
			(teardrops
				(best_length_ratio 0.2)
				(max_length 1)
				(best_width_ratio 0.9)
				(max_width 2)
				(curved_edges yes)
				(filter_ratio 0.9)
				(enabled yes)
				(allow_two_segments yes)
				(prefer_zone_connections yes)
			)
		)
		(pad "2" smd roundrect
			(at 1.5 0.001 180)
			(size 1.15 1.8)
			(layers "F.Cu" "F.Mask" "F.Paste")
			(roundrect_rratio 0.25)
			(net 81 "/Misc/FAN_12V")
			(pintype "passive")
			(teardrops
				(best_length_ratio 0.2)
				(max_length 1)
				(best_width_ratio 0.9)
				(max_width 2)
				(curved_edges yes)
				(filter_ratio 0.9)
				(enabled yes)
				(allow_two_segments yes)
				(prefer_zone_connections yes)
			)
		)
	)
	(footprint "antmicro-footprints:Choke_0805_2012Metric"
		(layer "F.Cu")
		(at 127.25 101.61 180)
		(property "Reference" "T4"
			(at 1.65 -1.85 0)
			(unlocked yes)
			(layer "F.SilkS")
			(effects
				(font
					(size 0.7 0.7)
					(thickness 0.15)
				)
				(justify left bottom)
			)
		)
		(property "Value" "Choke_SRF2012A-801Y"
			(at 0 -7 180)
			(unlocked yes)
			(layer "F.Fab")
			(effects
				(font
					(size 0.7 0.7)
					(thickness 0.15)
				)
				(justify left bottom)
			)
		)
		(property "Datasheet" "https://www.bourns.com/docs/product-datasheets/srf2012a-801y.pdf"
			(at 0 0 180)
			(layer "F.Fab")
			(hide yes)
			(effects
				(font
					(size 1.27 1.27)
					(thickness 0.15)
				)
			)
		)
		(property "Author" "Antmicro"
			(at 254.5 203.22 0)
			(layer "F.Fab")
			(hide yes)
			(effects
				(font
					(size 1 1)
					(thickness 0.15)
				)
			)
		)
		(property "IMax" "0.3 A"
			(at 254.5 203.22 0)
			(layer "F.Fab")
			(hide yes)
			(effects
				(font
					(size 1 1)
					(thickness 0.15)
				)
			)
		)
		(property "License" "Apache-2.0"
			(at 254.5 203.22 0)
			(layer "F.Fab")
			(hide yes)
			(effects
				(font
					(size 1 1)
					(thickness 0.15)
				)
			)
		)
		(property "MPN" "SRF2012A-801Y"
			(at 254.5 203.22 0)
			(layer "F.Fab")
			(hide yes)
			(effects
				(font
					(size 1 1)
					(thickness 0.15)
				)
			)
		)
		(property "Manufacturer" "Bourns"
			(at 254.5 203.22 0)
			(layer "F.Fab")
			(hide yes)
			(effects
				(font
					(size 1 1)
					(thickness 0.15)
				)
			)
		)
		(property "Public" "False"
			(at 254.5 203.22 0)
			(layer "F.Fab")
			(hide yes)
			(effects
				(font
					(size 1 1)
					(thickness 0.15)
				)
			)
		)
		(property ki_fp_filters "IND_ACM9070_TDK")
		(sheetname "2xUSB3.0+RJ45")
		(sheetfile "usb3+rj45.kicad_sch")
		(attr smd)
		(fp_rect
			(start -1.5 -0.9)
			(end 1.5 0.9)
			(stroke
				(width 0.05)
				(type solid)
			)
			(fill no)
			(layer "F.CrtYd")
		)
		(pad "1" smd roundrect
			(at -0.96 -0.46 180)
			(size 0.675 0.475)
			(layers "F.Cu" "F.Mask" "F.Paste")
			(roundrect_rratio 0.25)
			(net 695 "/2xUSB3.0+RJ45/DD_FL+")
			(pinfunction "1")
			(pintype "passive")
			(teardrops
				(best_length_ratio 0.2)
				(max_length 1)
				(best_width_ratio 0.9)
				(max_width 2)
				(curved_edges yes)
				(filter_ratio 0.9)
				(enabled yes)
				(allow_two_segments yes)
				(prefer_zone_connections yes)
			)
		)
		(pad "2" smd roundrect
			(at 0.96 -0.46 180)
			(size 0.675 0.475)
			(layers "F.Cu" "F.Mask" "F.Paste")
			(roundrect_rratio 0.25)
			(net 152 "/2xUSB3.0+RJ45/DD+")
			(pinfunction "2")
			(pintype "passive")
			(teardrops
				(best_length_ratio 0.2)
				(max_length 1)
				(best_width_ratio 0.9)
				(max_width 2)
				(curved_edges yes)
				(filter_ratio 0.9)
				(enabled yes)
				(allow_two_segments yes)
				(prefer_zone_connections yes)
			)
		)
		(pad "3" smd roundrect
			(at 0.96 0.46 180)
			(size 0.675 0.475)
			(layers "F.Cu" "F.Mask" "F.Paste")
			(roundrect_rratio 0.25)
			(net 153 "/2xUSB3.0+RJ45/DD-")
			(pinfunction "3")
			(pintype "passive")
			(teardrops
				(best_length_ratio 0.2)
				(max_length 1)
				(best_width_ratio 0.9)
				(max_width 2)
				(curved_edges yes)
				(filter_ratio 0.9)
				(enabled yes)
				(allow_two_segments yes)
				(prefer_zone_connections yes)
			)
		)
		(pad "4" smd roundrect
			(at -0.96 0.46 180)
			(size 0.675 0.475)
			(layers "F.Cu" "F.Mask" "F.Paste")
			(roundrect_rratio 0.25)
			(net 696 "/2xUSB3.0+RJ45/DD_FL-")
			(pinfunction "4")
			(pintype "passive")
			(teardrops
				(best_length_ratio 0.2)
				(max_length 1)
				(best_width_ratio 0.9)
				(max_width 2)
				(curved_edges yes)
				(filter_ratio 0.9)
				(enabled yes)
				(allow_two_segments yes)
				(prefer_zone_connections yes)
			)
		)
	)
	(footprint "antmicro-footprints:R_0201"
		(layer "F.Cu")
		(at 138.172 147.935 -90)
		(descr "Resistor SMD 0201")
		(tags "resistor SMD 0201")
		(property "Reference" "R288"
			(at 6.476 -0.578 270)
			(layer "F.SilkS")
			(effects
				(font
					(size 0.7 0.7)
					(thickness 0.15)
				)
				(justify left bottom)
			)
		)
		(property "Value" "R_0R_0201"
			(at 0 1.25 270)
			(layer "F.Fab")
			(effects
				(font
					(size 0.7 0.7)
					(thickness 0.15)
				)
				(justify left bottom)
			)
		)
		(property "Datasheet" "https://www.bourns.com/docs/product-datasheets/cr.pdf"
			(at 0 0 270)
			(layer "F.Fab")
			(hide yes)
			(effects
				(font
					(size 1.27 1.27)
					(thickness 0.15)
				)
			)
		)
		(property "Author" "Antmicro"
			(at -9.763 286.107 0)
			(layer "F.Fab")
			(hide yes)
			(effects
				(font
					(size 1 1)
					(thickness 0.15)
				)
			)
		)
		(property "License" "Apache-2.0"
			(at -9.763 286.107 0)
			(layer "F.Fab")
			(hide yes)
			(effects
				(font
					(size 1 1)
					(thickness 0.15)
				)
			)
		)
		(property "MPN" "CR0201-FX-0R00GLF"
			(at -9.763 286.107 0)
			(layer "F.Fab")
			(hide yes)
			(effects
				(font
					(size 1 1)
					(thickness 0.15)
				)
			)
		)
		(property "Manufacturer" "Bourns"
			(at -9.763 286.107 0)
			(layer "F.Fab")
			(hide yes)
			(effects
				(font
					(size 1 1)
					(thickness 0.15)
				)
			)
		)
		(property "Tolerance" "1%"
			(at -9.763 286.107 0)
			(layer "F.Fab")
			(hide yes)
			(effects
				(font
					(size 1 1)
					(thickness 0.15)
				)
			)
		)
		(property "Val" "0R"
			(at -9.763 286.107 0)
			(layer "F.Fab")
			(hide yes)
			(effects
				(font
					(size 1 1)
					(thickness 0.15)
				)
			)
		)
		(sheetname "KR to SFI #2")
		(sheetfile "kr_sfi.kicad_sch")
		(attr smd dnp)
		(fp_rect
			(start -0.7 -0.35)
			(end 0.7 0.35)
			(stroke
				(width 0.05)
				(type default)
			)
			(fill no)
			(layer "F.CrtYd")
		)
		(fp_rect
			(start -0.3 -0.15)
			(end 0.298 0.148)
			(stroke
				(width 0.15)
				(type solid)
			)
			(fill no)
			(layer "F.Fab")
		)
		(pad "" smd roundrect
			(at -0.346 0 270)
			(size 0.318 0.36)
			(layers "F.Paste")
			(roundrect_rratio 0.25)
			(teardrops
				(best_length_ratio 0.2)
				(max_length 1)
				(best_width_ratio 0.9)
				(max_width 2)
				(curved_edges yes)
				(filter_ratio 0.9)
				(enabled yes)
				(allow_two_segments yes)
				(prefer_zone_connections yes)
			)
		)
		(pad "" smd roundrect
			(at 0.344 0 270)
			(size 0.318 0.36)
			(layers "F.Paste")
			(roundrect_rratio 0.25)
			(teardrops
				(best_length_ratio 0.2)
				(max_length 1)
				(best_width_ratio 0.9)
				(max_width 2)
				(curved_edges yes)
				(filter_ratio 0.9)
				(enabled yes)
				(allow_two_segments yes)
				(prefer_zone_connections yes)
			)
		)
		(pad "1" smd roundrect
			(at -0.32 0 270)
			(size 0.46 0.4)
			(layers "F.Cu" "F.Mask")
			(roundrect_rratio 0.25)
			(net 121 "/2xSFP+/10GKR_SFP1.TX-")
			(pintype "passive")
			(teardrops
				(best_length_ratio 0.2)
				(max_length 1)
				(best_width_ratio 0.9)
				(max_width 2)
				(curved_edges yes)
				(filter_ratio 0.9)
				(enabled yes)
				(allow_two_segments yes)
				(prefer_zone_connections yes)
			)
		)
		(pad "2" smd roundrect
			(at 0.32 0 270)
			(size 0.46 0.4)
			(layers "F.Cu" "F.Mask")
			(roundrect_rratio 0.25)
			(net 951 "/2xSFP+/KR to SFI #2/BYP_TX-")
			(pintype "passive")
			(teardrops
				(best_length_ratio 0.2)
				(max_length 1)
				(best_width_ratio 0.9)
				(max_width 2)
				(curved_edges yes)
				(filter_ratio 0.9)
				(enabled yes)
				(allow_two_segments yes)
				(prefer_zone_connections yes)
			)
		)
	)
	(footprint "antmicro-footprints:LED_0603_1608Metric_G"
		(layer "F.Cu")
		(at 110.9 69.86 90)
		(descr "LED SMD 0603 Green")
		(tags "LED SMD 0603 Green")
		(property "Reference" "D12"
			(at -3.45 0.4 90)
			(layer "F.SilkS")
			(effects
				(font
					(size 0.7 0.7)
					(thickness 0.15)
				)
				(justify left bottom)
			)
		)
		(property "Value" "LED_G_0603_LTST-C190GKT"
			(at -0.001 1.599 90)
			(layer "F.Fab")
			(effects
				(font
					(size 0.7 0.7)
					(thickness 0.15)
				)
				(justify left bottom)
			)
		)
		(property "Datasheet" "https://media.digikey.com/pdf/Data%20Sheets/Lite-On%20PDFs/LTST-C190GKT.pdf"
			(at 0 0 90)
			(layer "F.Fab")
			(hide yes)
			(effects
				(font
					(size 1.27 1.27)
					(thickness 0.15)
				)
			)
		)
		(property "Author" "Antmicro"
			(at 180.76 -41.04 0)
			(layer "F.Fab")
			(hide yes)
			(effects
				(font
					(size 1 1)
					(thickness 0.15)
				)
			)
		)
		(property "Color" "Green"
			(at 180.76 -41.04 0)
			(layer "F.Fab")
			(hide yes)
			(effects
				(font
					(size 1 1)
					(thickness 0.15)
				)
			)
		)
		(property "License" "Apache-2.0"
			(at 180.76 -41.04 0)
			(layer "F.Fab")
			(hide yes)
			(effects
				(font
					(size 1 1)
					(thickness 0.15)
				)
			)
		)
		(property "MPN" "LTST-C190GKT"
			(at 180.76 -41.04 0)
			(layer "F.Fab")
			(hide yes)
			(effects
				(font
					(size 1 1)
					(thickness 0.15)
				)
			)
		)
		(property "Manufacturer" "Lite-On"
			(at 180.76 -41.04 0)
			(layer "F.Fab")
			(hide yes)
			(effects
				(font
					(size 1 1)
					(thickness 0.15)
				)
			)
		)
		(property "Public" "False"
			(at 180.76 -41.04 0)
			(layer "F.Fab")
			(hide yes)
			(effects
				(font
					(size 1 1)
					(thickness 0.15)
				)
			)
		)
		(sheetname "USB-C console")
		(sheetfile "usb-c_console.kicad_sch")
		(attr smd)
		(fp_line
			(start 0.22 -0.35)
			(end -0.22 -0.35)
			(stroke
				(width 0.15)
				(type solid)
			)
			(layer "F.SilkS")
		)
		(fp_line
			(start -1.18 -0.319)
			(end -1.18 0.321)
			(stroke
				(width 0.15)
				(type solid)
			)
			(layer "F.SilkS")
		)
		(fp_line
			(start 0.105328 0.001008)
			(end 0.24 0.001)
			(stroke
				(width 0.1)
				(type solid)
			)
			(layer "F.SilkS")
		)
		(fp_line
			(start -0.094672 0.001008)
			(end 0.105328 -0.198992)
			(stroke
				(width 0.1)
				(type solid)
			)
			(layer "F.SilkS")
		)
		(fp_line
			(start -0.094672 0.001008)
			(end -0.24 0.001008)
			(stroke
				(width 0.1)
				(type solid)
			)
			(layer "F.SilkS")
		)
		(fp_line
			(start 0.105328 0.201008)
			(end 0.105328 -0.198992)
			(stroke
				(width 0.1)
				(type solid)
			)
			(layer "F.SilkS")
		)
		(fp_line
			(start 0.105328 0.201008)
			(end -0.094672 0.001008)
			(stroke
				(width 0.1)
				(type solid)
			)
			(layer "F.SilkS")
		)
		(fp_line
			(start -0.094672 0.201008)
			(end -0.094672 -0.198992)
			(stroke
				(width 0.1)
				(type solid)
			)
			(layer "F.SilkS")
		)
		(fp_line
			(start 0.22 0.35)
			(end -0.22 0.35)
			(stroke
				(width 0.15)
				(type solid)
			)
			(layer "F.SilkS")
		)
		(fp_rect
			(start 1.25 0.65)
			(end -1.25 -0.65)
			(stroke
				(width 0.05)
				(type solid)
			)
			(fill no)
			(layer "F.CrtYd")
		)
		(fp_line
			(start 0.201 -0.202)
			(end -0.101 0)
			(stroke
				(width 0.15)
				(type solid)
			)
			(layer "F.Fab")
		)
		(fp_line
			(start -0.199 -0.202)
			(end -0.199 0.1)
			(stroke
				(width 0.15)
				(type solid)
			)
			(layer "F.Fab")
		)
		(fp_line
			(start 0.599 0)
			(end 0.201 0)
			(stroke
				(width 0.15)
				(type solid)
			)
			(layer "F.Fab")
		)
		(fp_line
			(start 0.201 0)
			(end 0.201 -0.202)
			(stroke
				(width 0.15)
				(type solid)
			)
			(layer "F.Fab")
		)
		(fp_line
			(start -0.101 0)
			(end 0.201 0.2)
			(stroke
				(width 0.15)
				(type solid)
			)
			(layer "F.Fab")
		)
		(fp_line
			(start -0.199 0)
			(end -0.597 0)
			(stroke
				(width 0.15)
				(type solid)
			)
			(layer "F.Fab")
		)
		(fp_line
			(start 0.201 0.2)
			(end 0.201 0)
			(stroke
				(width 0.15)
				(type solid)
			)
			(layer "F.Fab")
		)
		(fp_line
			(start -0.199 0.2)
			(end -0.199 0.1)
			(stroke
				(width 0.15)
				(type solid)
			)
			(layer "F.Fab")
		)
		(fp_rect
			(start 0.848 0.4)
			(end -0.85 -0.402)
			(stroke
				(width 0.15)
				(type solid)
			)
			(fill no)
			(layer "F.Fab")
		)
		(pad "1" smd roundrect
			(at -0.7 0 270)
			(size 0.8 1)
			(layers "F.Cu" "F.Mask" "F.Paste")
			(roundrect_rratio 0.2)
			(net 128 "/USB-C console/FTDI_LED_TX")
			(pinfunction "C")
			(pintype "passive")
			(teardrops
				(best_length_ratio 0.2)
				(max_length 1)
				(best_width_ratio 0.9)
				(max_width 2)
				(curved_edges yes)
				(filter_ratio 0.9)
				(enabled yes)
				(allow_two_segments yes)
				(prefer_zone_connections yes)
			)
		)
		(pad "2" smd roundrect
			(at 0.7 0 270)
			(size 0.8 1)
			(layers "F.Cu" "F.Mask" "F.Paste")
			(roundrect_rratio 0.2)
			(net 934 "Net-(D12-A)")
			(pinfunction "A")
			(pintype "passive")
			(teardrops
				(best_length_ratio 0.2)
				(max_length 1)
				(best_width_ratio 0.9)
				(max_width 2)
				(curved_edges yes)
				(filter_ratio 0.9)
				(enabled yes)
				(allow_two_segments yes)
				(prefer_zone_connections yes)
			)
		)
	)
)
